# BASEBOARD_FAB2 (Tioga Pass) — schematic netlist excerpt (pin names and nets, part order shuffled) for the footprints in the layout excerpt that follows; sources: Cadence DE-HDL packaged netlist, KiCad conversion of Wiwynn_Tioga_Pass_MB.brd

C2M17  CAP  47UF 4V 20% X6S  pkg 0805  page 131 : A = P1V05_PCH_STBY ; B = GND
R3R2  RES  1.00K 1% CHIP  pkg 0402  page 92 : A = H_CPU1_FIVR_FAULT_G ; B = GND
R1U27  RES  3.48K 1.0% CHIP  pkg 0402  page 169 : A = A_P3V3_SCALED ; B = GND

(kicad_pcb
	(version 20260206)
	(generator "pcbnew")
	(generator_version "10.0")
	(general
		(thickness 1.6)
		(legacy_teardrops no)
	)
	(paper "A4")
	(title_block
		(title "Wiwynn_Tioga_Pass_MB.brd")
		(comment 1 "Tioga Pass / footprints 2470-2472 of 4770")
	)
	(layers
		(0 "F.Cu" signal "TOP")
		(4 "In1.Cu" signal "L2GND")
		(6 "In2.Cu" signal "L3")
		(8 "In3.Cu" signal "L4GND")
		(10 "In4.Cu" signal "L5")
		(12 "In5.Cu" signal "L6GND")
		(14 "In6.Cu" signal "L7VCC")
		(16 "In7.Cu" signal "L8VCC")
		(18 "In8.Cu" signal "L9GND")
		(20 "In9.Cu" signal "L10")
		(22 "In10.Cu" signal "L11GND")
		(24 "In11.Cu" signal "L12")
		(26 "In12.Cu" signal "L13GND")
		(2 "B.Cu" signal "BOTTOM")
		(9 "F.Adhes" user "F.Adhesive")
		(11 "B.Adhes" user "B.Adhesive")
		(13 "F.Paste" user "Package Geometry/Pastemask Top")
		(15 "B.Paste" user "Package Geometry/Pastemask Bottom")
		(5 "F.SilkS" user "Ref Des/Silkscreen Top")
		(7 "B.SilkS" user "Ref Des/Silkscreen Bottom")
		(1 "F.Mask" user "Board Geometry/Soldermask Top")
		(3 "B.Mask" user "Board Geometry/Soldermask Bottom")
		(17 "Dwgs.User" user "User.Drawings")
		(19 "Cmts.User" user "User.Comments")
		(21 "Eco1.User" user "User.Eco1")
		(23 "Eco2.User" user "User.Eco2")
		(25 "Edge.Cuts" user "Board Geometry/Outline")
		(27 "Margin" user)
		(31 "F.CrtYd" user "Package Geometry/Place Bound Top")
		(29 "B.CrtYd" user "Package Geometry/Place Bound Bottom")
		(35 "F.Fab" user "Ref Des/Assembly Top")
		(33 "B.Fab" user "Ref Des/Assembly Bottom")
	)
	(footprint ""
		(layer "B.Cu")
		(at 402.2344 -23.114 90)
		(property "Reference" "R1U27"
			(at 0 0 90)
			(layer "B.SilkS")
			(hide yes)
			(effects
				(font
					(size 1.27 1.27)
				)
				(justify mirror)
			)
		)
		(property "Value" ""
			(at 0 0 90)
			(layer "B.Fab")
			(effects
				(font
					(size 1.27 1.27)
				)
				(justify mirror)
			)
		)
		(duplicate_pad_numbers_are_jumpers no)
		(fp_poly
			(pts
				(xy 0.2794 -0.1016) (xy -0.2794 -0.1016) (xy -0.2794 0.9906) (xy 0.2794 0.9906)
			)
			(stroke
				(width 0)
				(type default)
			)
			(fill no)
			(layer "B.CrtYd")
		)
		(fp_line
			(start 0.2794 -0.1016)
			(end 0.2794 0.9906)
			(stroke
				(width 0.1)
				(type default)
			)
			(layer "B.Fab")
		)
		(fp_line
			(start -0.2794 -0.1016)
			(end 0.2794 -0.1016)
			(stroke
				(width 0.1)
				(type default)
			)
			(layer "B.Fab")
		)
		(fp_line
			(start 0.2794 0.9906)
			(end -0.2794 0.9906)
			(stroke
				(width 0.1)
				(type default)
			)
			(layer "B.Fab")
		)
		(fp_line
			(start -0.2794 0.9906)
			(end -0.2794 -0.1016)
			(stroke
				(width 0.1)
				(type default)
			)
			(layer "B.Fab")
		)
		(pad "1" smd rect
			(at 0 0 270)
			(size 0.508 0.508)
			(layers "B.Cu" "B.Mask" "B.Paste")
			(net "A_P3V3_SCALED")
		)
		(pad "2" smd rect
			(at 0 0.889 270)
			(size 0.508 0.508)
			(layers "B.Cu" "B.Mask" "B.Paste")
			(net "GND")
		)
		(zone
			(layer "B.Cu")
			(hatch none 0.5)
			(connect_pads
				(clearance 0)
			)
			(min_thickness 0.25)
			(keepout
				(tracks allowed)
				(vias not_allowed)
				(pads allowed)
				(copperpour not_allowed)
				(footprints allowed)
			)
			(placement
				(enabled no)
				(sheetname "")
			)
			(fill
				(thermal_gap 0.5)
				(thermal_bridge_width 0.5)
				(island_removal_mode 0)
			)
			(polygon
				(pts
					(xy 402.4884 -23.368) (xy 402.4884 -22.86) (xy 402.8694 -22.86) (xy 402.8694 -23.368)
				)
			)
		)
		(zone
			(layer "B.Cu")
			(hatch none 0.5)
			(connect_pads
				(clearance 0)
			)
			(min_thickness 0.25)
			(keepout
				(tracks not_allowed)
				(vias allowed)
				(pads allowed)
				(copperpour not_allowed)
				(footprints allowed)
			)
			(placement
				(enabled no)
				(sheetname "")
			)
			(fill
				(thermal_gap 0.5)
				(thermal_bridge_width 0.5)
				(island_removal_mode 0)
			)
			(polygon
				(pts
					(xy 402.8694 -23.368) (xy 402.8694 -22.86) (xy 402.4884 -22.86) (xy 402.4884 -23.368)
				)
			)
		)
	)
	(footprint ""
		(layer "B.Cu")
		(at 406.680924 -114.9858 180)
		(property "Reference" "C2M17"
			(at 0 0 0)
			(layer "B.SilkS")
			(hide yes)
			(effects
				(font
					(size 1.27 1.27)
				)
				(justify mirror)
			)
		)
		(property "Value" ""
			(at 0 0 0)
			(layer "B.Fab")
			(effects
				(font
					(size 1.27 1.27)
				)
				(justify mirror)
			)
		)
		(duplicate_pad_numbers_are_jumpers no)
		(fp_poly
			(pts
				(xy 0.7239 -0.2159) (xy -0.7239 -0.2159) (xy -0.7239 1.9939) (xy 0.7239 1.9939)
			)
			(stroke
				(width 0)
				(type default)
			)
			(fill no)
			(layer "B.CrtYd")
		)
		(fp_line
			(start 0.7239 1.9939)
			(end -0.7239 1.9939)
			(stroke
				(width 0.1)
				(type default)
			)
			(layer "B.Fab")
		)
		(fp_line
			(start 0.7239 -0.2159)
			(end 0.7239 1.9939)
			(stroke
				(width 0.1)
				(type default)
			)
			(layer "B.Fab")
		)
		(fp_line
			(start -0.7239 1.9939)
			(end -0.7239 -0.2159)
			(stroke
				(width 0.1)
				(type default)
			)
			(layer "B.Fab")
		)
		(fp_line
			(start -0.7239 -0.2159)
			(end 0.7239 -0.2159)
			(stroke
				(width 0.1)
				(type default)
			)
			(layer "B.Fab")
		)
		(pad "1" smd rect
			(at 0 0)
			(size 1.27 1.016)
			(layers "B.Cu" "B.Mask" "B.Paste")
			(net "P1V05_PCH_STBY")
		)
		(pad "2" smd rect
			(at 0 1.778)
			(size 1.27 1.016)
			(layers "B.Cu" "B.Mask" "B.Paste")
			(net "GND")
		)
		(zone
			(layer "B.Cu")
			(hatch none 0.5)
			(connect_pads
				(clearance 0)
			)
			(min_thickness 0.25)
			(keepout
				(tracks not_allowed)
				(vias allowed)
				(pads allowed)
				(copperpour not_allowed)
				(footprints allowed)
			)
			(placement
				(enabled no)
				(sheetname "")
			)
			(fill
				(thermal_gap 0.5)
				(thermal_bridge_width 0.5)
				(island_removal_mode 0)
			)
			(polygon
				(pts
					(xy 406.045924 -115.4938) (xy 407.315924 -115.4938) (xy 407.315924 -116.2558) (xy 406.045924 -116.2558)
				)
			)
		)
	)
	(footprint ""
		(layer "B.Cu")
		(at 370.459 -62.357 180)
		(property "Reference" "R3R2"
			(at 0 0 0)
			(layer "B.SilkS")
			(hide yes)
			(effects
				(font
					(size 1.27 1.27)
				)
				(justify mirror)
			)
		)
		(property "Value" ""
			(at 0 0 0)
			(layer "B.Fab")
			(effects
				(font
					(size 1.27 1.27)
				)
				(justify mirror)
			)
		)
		(duplicate_pad_numbers_are_jumpers no)
		(fp_poly
			(pts
				(xy 0.2794 -0.1016) (xy -0.2794 -0.1016) (xy -0.2794 0.9906) (xy 0.2794 0.9906)
			)
			(stroke
				(width 0)
				(type default)
			)
			(fill no)
			(layer "B.CrtYd")
		)
		(fp_line
			(start 0.2794 0.9906)
			(end -0.2794 0.9906)
			(stroke
				(width 0.1)
				(type default)
			)
			(layer "B.Fab")
		)
		(fp_line
			(start 0.2794 -0.1016)
			(end 0.2794 0.9906)
			(stroke
				(width 0.1)
				(type default)
			)
			(layer "B.Fab")
		)
		(fp_line
			(start -0.2794 0.9906)
			(end -0.2794 -0.1016)
			(stroke
				(width 0.1)
				(type default)
			)
			(layer "B.Fab")
		)
		(fp_line
			(start -0.2794 -0.1016)
			(end 0.2794 -0.1016)
			(stroke
				(width 0.1)
				(type default)
			)
			(layer "B.Fab")
		)
		(pad "1" smd rect
			(at 0 0)
			(size 0.508 0.508)
			(layers "B.Cu" "B.Mask" "B.Paste")
			(net "H_CPU1_FIVR_FAULT_G")
		)
		(pad "2" smd rect
			(at 0 0.889)
			(size 0.508 0.508)
			(layers "B.Cu" "B.Mask" "B.Paste")
			(net "GND")
		)
		(zone
			(layer "B.Cu")
			(hatch none 0.5)
			(connect_pads
				(clearance 0)
			)
			(min_thickness 0.25)
			(keepout
				(tracks not_allowed)
				(vias allowed)
				(pads allowed)
				(copperpour not_allowed)
				(footprints allowed)
			)
			(placement
				(enabled no)
				(sheetname "")
			)
			(fill
				(thermal_gap 0.5)
				(thermal_bridge_width 0.5)
				(island_removal_mode 0)
			)
			(polygon
				(pts
					(xy 370.205 -62.992) (xy 370.713 -62.992) (xy 370.713 -62.611) (xy 370.205 -62.611)
				)
			)
		)
		(zone
			(layer "B.Cu")
			(hatch none 0.5)
			(connect_pads
				(clearance 0)
			)
			(min_thickness 0.25)
			(keepout
				(tracks allowed)
				(vias not_allowed)
				(pads allowed)
				(copperpour not_allowed)
				(footprints allowed)
			)
			(placement
				(enabled no)
				(sheetname "")
			)
			(fill
				(thermal_gap 0.5)
				(thermal_bridge_width 0.5)
				(island_removal_mode 0)
			)
			(polygon
				(pts
					(xy 370.205 -62.611) (xy 370.713 -62.611) (xy 370.713 -62.992) (xy 370.205 -62.992)
				)
			)
		)
	)
)
